FILE_TYPE = CONNECTIVITY;
{Allegro Design Entry HDL 17.2-2016 S081 (4005846) 1/11/2022}
"PAGE_NUMBER" = 27;
0"NC";
1"M_H_CPU0_SA_CA<6:0>";
2"M_H_CPU0_SA_CS_N<3:0>";
3"M_H_CPU0_SA_DQS_DN<9:0>";
4"M_H_CPU0_SA_DQS_DP<9:0>";
5"M_H_CPU0_SB_CA<6:0>";
6"M_H_CPU0_SB_CS_N<3:0>";
7"M_H_CPU0_SB_DQS_DN<9:0>";
8"M_H_CPU0_SB_DQS_DP<9:0>";
9"M_H_CPU0_SB_CB<7:0>";
10"M_H_CPU0_SB_DQ<31:0>";
11"M_H_CPU0_SA_CB<7:0>";
12"M_H_CPU0_SA_DQ<31:0>";
13"M_H_CPU0_CLK_DP<1:0>";
14"M_H_CPU0_CLK_DN<1:0>";
15"M_H_CPU0_CLK_DN<1>";
16"M_H_CPU0_CLK_DN<0>";
17"M_H_CPU0_CLK_DP<1>";
18"M_H_CPU0_CLK_DP<0>";
19"M_H_CPU0_SA_DQ<31>";
20"M_H_CPU0_SA_DQ<30>";
21"M_H_CPU0_SA_DQ<29>";
22"M_H_CPU0_SA_DQ<28>";
23"M_H_CPU0_SA_DQ<27>";
24"M_H_CPU0_SA_DQ<26>";
25"M_H_CPU0_SA_DQ<25>";
26"M_H_CPU0_SA_DQ<24>";
27"M_H_CPU0_SA_DQ<23>";
28"M_H_CPU0_SA_DQ<22>";
29"M_H_CPU0_SA_DQ<21>";
30"M_H_CPU0_SA_DQ<20>";
31"M_H_CPU0_SA_DQ<19>";
32"M_H_CPU0_SA_DQ<18>";
33"M_H_CPU0_SA_DQ<17>";
34"M_H_CPU0_SA_DQ<16>";
35"M_H_CPU0_SA_DQ<15>";
36"M_H_CPU0_SA_DQ<14>";
37"M_H_CPU0_SA_DQ<13>";
38"M_H_CPU0_SA_DQ<12>";
39"M_H_CPU0_SA_DQ<11>";
40"M_H_CPU0_SA_DQ<10>";
41"M_H_CPU0_SA_DQ<9>";
42"M_H_CPU0_SA_DQ<8>";
43"M_H_CPU0_SA_DQ<7>";
44"M_H_CPU0_SA_DQ<6>";
45"M_H_CPU0_SA_DQ<5>";
46"M_H_CPU0_SA_DQ<4>";
47"M_H_CPU0_SA_DQ<3>";
48"M_H_CPU0_SA_DQ<2>";
49"M_H_CPU0_SA_DQ<1>";
50"M_H_CPU0_SA_DQ<0>";
51"M_H_CPU0_SA_CB<7>";
52"M_H_CPU0_SA_CB<6>";
53"M_H_CPU0_SA_CB<5>";
54"M_H_CPU0_SA_CB<4>";
55"M_H_CPU0_SA_CB<3>";
56"M_H_CPU0_SA_CB<2>";
57"M_H_CPU0_SA_CB<1>";
58"M_H_CPU0_SA_CB<0>";
59"M_H_CPU0_SB_DQ<31>";
60"M_H_CPU0_SB_DQ<30>";
61"M_H_CPU0_SB_DQ<29>";
62"M_H_CPU0_SB_DQ<28>";
63"M_H_CPU0_SB_DQ<27>";
64"M_H_CPU0_SB_DQ<26>";
65"M_H_CPU0_SB_DQ<25>";
66"M_H_CPU0_SB_DQ<24>";
67"M_H_CPU0_SB_DQ<23>";
68"M_H_CPU0_SB_DQ<22>";
69"M_H_CPU0_SB_DQ<21>";
70"M_H_CPU0_SB_DQ<20>";
71"M_H_CPU0_SB_DQ<19>";
72"M_H_CPU0_SB_DQ<18>";
73"M_H_CPU0_SB_DQ<17>";
74"M_H_CPU0_SB_DQ<16>";
75"M_H_CPU0_SB_DQ<15>";
76"M_H_CPU0_SB_DQ<14>";
77"M_H_CPU0_SB_DQ<13>";
78"M_H_CPU0_SB_DQ<12>";
79"M_H_CPU0_SB_DQ<11>";
80"M_H_CPU0_SB_DQ<10>";
81"M_H_CPU0_SB_DQ<9>";
82"M_H_CPU0_SB_DQ<8>";
83"M_H_CPU0_SB_DQ<7>";
84"M_H_CPU0_SB_DQ<6>";
85"M_H_CPU0_SB_DQ<5>";
86"M_H_CPU0_SB_DQ<4>";
87"M_H_CPU0_SB_DQ<3>";
88"M_H_CPU0_SB_DQ<2>";
89"M_H_CPU0_SB_DQ<1>";
90"M_H_CPU0_SB_DQ<0>";
91"M_H_CPU0_SB_CB<7>";
92"M_H_CPU0_SB_CB<6>";
93"M_H_CPU0_SB_CB<5>";
94"M_H_CPU0_SB_CB<4>";
95"M_H_CPU0_SB_CB<3>";
96"M_H_CPU0_SB_CB<2>";
97"M_H_CPU0_SB_CB<1>";
98"M_H_CPU0_SB_CB<0>";
99"M_H_CPU0_SB_PAR";
100"M_H_CPU0_SB_DQS_DP<0>";
101"M_H_CPU0_SB_DQS_DP<1>";
102"M_H_CPU0_SB_DQS_DP<2>";
103"M_H_CPU0_SB_DQS_DP<3>";
104"M_H_CPU0_SB_DQS_DP<4>";
105"M_H_CPU0_SB_DQS_DP<5>";
106"M_H_CPU0_SB_DQS_DP<6>";
107"M_H_CPU0_SB_DQS_DP<7>";
108"M_H_CPU0_SB_DQS_DP<8>";
109"M_H_CPU0_SB_DQS_DP<9>";
110"M_H_CPU0_SB_DQS_DN<0>";
111"M_H_CPU0_SB_DQS_DN<1>";
112"M_H_CPU0_SB_DQS_DN<2>";
113"M_H_CPU0_SB_DQS_DN<3>";
114"M_H_CPU0_SB_DQS_DN<4>";
115"M_H_CPU0_SB_DQS_DN<5>";
116"M_H_CPU0_SB_DQS_DN<6>";
117"M_H_CPU0_SB_DQS_DN<7>";
118"M_H_CPU0_SB_DQS_DN<8>";
119"M_H_CPU0_SB_DQS_DN<9>";
120"M_H_CPU0_SB_CS_N<0>";
121"M_H_CPU0_SB_CS_N<1>";
122"M_H_CPU0_SB_CS_N<2>";
123"M_H_CPU0_SB_CS_N<3>";
124"M_H_CPU0_SB_CA<0>";
125"M_H_CPU0_SB_CA<1>";
126"M_H_CPU0_SB_CA<2>";
127"M_H_CPU0_SB_CA<3>";
128"M_H_CPU0_SB_CA<4>";
129"M_H_CPU0_SB_CA<5>";
130"M_H_CPU0_SB_CA<6>";
131"M_H_CPU0_SA_PAR";
132"M_H_CPU0_SA_DQS_DP<0>";
133"M_H_CPU0_SA_DQS_DP<1>";
134"M_H_CPU0_SA_DQS_DP<2>";
135"M_H_CPU0_SA_DQS_DP<3>";
136"M_H_CPU0_SA_DQS_DP<4>";
137"M_H_CPU0_SA_DQS_DP<5>";
138"M_H_CPU0_SA_DQS_DP<6>";
139"M_H_CPU0_SA_DQS_DP<7>";
140"M_H_CPU0_SA_DQS_DP<8>";
141"M_H_CPU0_SA_DQS_DP<9>";
142"M_H_CPU0_SA_DQS_DN<0>";
143"M_H_CPU0_SA_DQS_DN<1>";
144"M_H_CPU0_SA_DQS_DN<2>";
145"M_H_CPU0_SA_DQS_DN<3>";
146"M_H_CPU0_SA_DQS_DN<4>";
147"M_H_CPU0_SA_DQS_DN<5>";
148"M_H_CPU0_SA_DQS_DN<6>";
149"M_H_CPU0_SA_DQS_DN<7>";
150"M_H_CPU0_SA_DQS_DN<8>";
151"M_H_CPU0_SA_DQS_DN<9>";
152"M_H_CPU0_SA_CS_N<0>";
153"M_H_CPU0_SA_CS_N<1>";
154"M_H_CPU0_SA_CS_N<2>";
155"M_H_CPU0_SA_CS_N<3>";
156"M_H_CPU0_SA_CA<0>";
157"M_H_CPU0_SA_CA<1>";
158"M_H_CPU0_SA_CA<2>";
159"M_H_CPU0_SA_CA<3>";
160"M_H_CPU0_SA_CA<4>";
161"M_H_CPU0_SA_CA<5>";
162"M_H_CPU0_SA_CA<6>";
163"M_H_CPU0_SB_RSP<0>";
164"M_H_CPU0_SB_RSP<1>";
165"M_H_CPU0_SA_RSP<0>";
166"M_H_CPU0_SA_RSP<1>";
167"M_H_CPU0_ALERT_N";
%"TAP"
"1","(2475,850)","0","standard","I100";
;
CDS_LIB"standard"
BODY_TYPE"PLUMBING"
HDL_TAP"TRUE";
"B \NAC \NWC"6;
"S \NAC"
BN"2"122;
%"TAP"
"1","(2475,1100)","0","standard","I101";
;
CDS_LIB"standard"
BODY_TYPE"PLUMBING"
HDL_TAP"TRUE";
"B \NAC \NWC"2;
"S \NAC"
BN"1"153;
%"TAP"
"1","(2475,1150)","0","standard","I102";
;
CDS_LIB"standard"
BODY_TYPE"PLUMBING"
HDL_TAP"TRUE";
"B \NAC \NWC"2;
"S \NAC"
BN"2"154;
%"TAP"
"1","(2475,1050)","0","standard","I103";
;
CDS_LIB"standard"
BODY_TYPE"PLUMBING"
HDL_TAP"TRUE";
"B \NAC \NWC"2;
"S \NAC"
BN"0"152;
%"TAP"
"1","(2475,1200)","0","standard","I104";
;
CDS_LIB"standard"
BODY_TYPE"PLUMBING"
HDL_TAP"TRUE";
"B \NAC \NWC"2;
"S \NAC"
BN"3"155;
%"TAP"
"1","(2475,1400)","0","standard","I105";
;
CDS_LIB"standard"
BODY_TYPE"PLUMBING"
HDL_TAP"TRUE";
"B \NAC \NWC"5;
"S \NAC"
BN"0"124;
%"TAP"
"1","(2475,1500)","0","standard","I106";
;
CDS_LIB"standard"
BODY_TYPE"PLUMBING"
HDL_TAP"TRUE";
"B \NAC \NWC"5;
"S \NAC"
BN"2"126;
%"TAP"
"1","(2475,1450)","0","standard","I107";
;
CDS_LIB"standard"
BODY_TYPE"PLUMBING"
HDL_TAP"TRUE";
"B \NAC \NWC"5;
"S \NAC"
BN"1"125;
%"TAP"
"1","(2475,1650)","0","standard","I108";
;
CDS_LIB"standard"
BODY_TYPE"PLUMBING"
HDL_TAP"TRUE";
"B \NAC \NWC"5;
"S \NAC"
BN"5"129;
%"TAP"
"1","(2475,1550)","0","standard","I109";
;
CDS_LIB"standard"
BODY_TYPE"PLUMBING"
HDL_TAP"TRUE";
"B \NAC \NWC"5;
"S \NAC"
BN"3"127;
%"TAP"
"1","(2475,1600)","0","standard","I110";
;
CDS_LIB"standard"
BODY_TYPE"PLUMBING"
HDL_TAP"TRUE";
"B \NAC \NWC"5;
"S \NAC"
BN"4"128;
%"TAP"
"1","(2475,1700)","0","standard","I111";
;
CDS_LIB"standard"
BODY_TYPE"PLUMBING"
HDL_TAP"TRUE";
"B \NAC \NWC"5;
"S \NAC"
BN"6"130;
%"TAP"
"1","(2475,1900)","0","standard","I112";
;
CDS_LIB"standard"
BODY_TYPE"PLUMBING"
HDL_TAP"TRUE";
"B \NAC \NWC"1;
"S \NAC"
BN"0"156;
%"TAP"
"1","(2475,2000)","0","standard","I113";
;
CDS_LIB"standard"
BODY_TYPE"PLUMBING"
HDL_TAP"TRUE";
"B \NAC \NWC"1;
"S \NAC"
BN"2"158;
%"TAP"
"1","(2475,1950)","0","standard","I114";
;
CDS_LIB"standard"
BODY_TYPE"PLUMBING"
HDL_TAP"TRUE";
"B \NAC \NWC"1;
"S \NAC"
BN"1"157;
%"TAP"
"1","(2475,2050)","0","standard","I115";
;
CDS_LIB"standard"
BODY_TYPE"PLUMBING"
HDL_TAP"TRUE";
"B \NAC \NWC"1;
"S \NAC"
BN"3"159;
%"TAP"
"1","(2475,2150)","0","standard","I116";
;
CDS_LIB"standard"
BODY_TYPE"PLUMBING"
HDL_TAP"TRUE";
"B \NAC \NWC"1;
"S \NAC"
BN"5"161;
%"TAP"
"1","(2475,2100)","0","standard","I117";
;
CDS_LIB"standard"
BODY_TYPE"PLUMBING"
HDL_TAP"TRUE";
"B \NAC \NWC"1;
"S \NAC"
BN"4"160;
%"TAP"
"1","(2475,2200)","0","standard","I118";
;
CDS_LIB"standard"
BODY_TYPE"PLUMBING"
HDL_TAP"TRUE";
"B \NAC \NWC"1;
"S \NAC"
BN"6"162;
%"TAP"
"1","(2475,2350)","0","standard","I119";
;
CDS_LIB"standard"
BODY_TYPE"PLUMBING"
HDL_TAP"TRUE";
"B \NAC \NWC"7;
"S \NAC"
BN"0"110;
%"TAP"
"1","(-950,750)","2","standard","I12";
;
CDS_LIB"standard"
BODY_TYPE"PLUMBING"
HDL_TAP"TRUE";
"B \NAC \NWC"9;
"S \NAC"
BN"4"94;
%"TAP"
"1","(2475,2400)","0","standard","I120";
;
CDS_LIB"standard"
BODY_TYPE"PLUMBING"
HDL_TAP"TRUE";
"B \NAC \NWC"7;
"S \NAC"
BN"1"111;
%"TAP"
"1","(2475,2450)","0","standard","I121";
;
CDS_LIB"standard"
BODY_TYPE"PLUMBING"
HDL_TAP"TRUE";
"B \NAC \NWC"7;
"S \NAC"
BN"2"112;
%"TAP"
"1","(2475,2500)","0","standard","I122";
;
CDS_LIB"standard"
BODY_TYPE"PLUMBING"
HDL_TAP"TRUE";
"B \NAC \NWC"7;
"S \NAC"
BN"3"113;
%"TAP"
"1","(2475,2550)","0","standard","I123";
;
CDS_LIB"standard"
BODY_TYPE"PLUMBING"
HDL_TAP"TRUE";
"B \NAC \NWC"7;
"S \NAC"
BN"4"114;
%"TAP"
"1","(2475,2650)","0","standard","I124";
;
CDS_LIB"standard"
BODY_TYPE"PLUMBING"
HDL_TAP"TRUE";
"B \NAC \NWC"7;
"S \NAC"
BN"6"116;
%"TAP"
"1","(2475,2600)","0","standard","I125";
;
CDS_LIB"standard"
BODY_TYPE"PLUMBING"
HDL_TAP"TRUE";
"B \NAC \NWC"7;
"S \NAC"
BN"5"115;
%"TAP"
"1","(2475,2800)","0","standard","I126";
;
CDS_LIB"standard"
BODY_TYPE"PLUMBING"
HDL_TAP"TRUE";
"B \NAC \NWC"7;
"S \NAC"
BN"9"119;
%"TAP"
"1","(2475,2750)","0","standard","I127";
;
CDS_LIB"standard"
BODY_TYPE"PLUMBING"
HDL_TAP"TRUE";
"B \NAC \NWC"7;
"S \NAC"
BN"8"118;
%"TAP"
"1","(2475,2700)","0","standard","I128";
;
CDS_LIB"standard"
BODY_TYPE"PLUMBING"
HDL_TAP"TRUE";
"B \NAC \NWC"7;
"S \NAC"
BN"7"117;
%"TAP"
"1","(2475,2900)","0","standard","I129";
;
CDS_LIB"standard"
BODY_TYPE"PLUMBING"
HDL_TAP"TRUE";
"B \NAC \NWC"8;
"S \NAC"
BN"0"100;
%"TAP"
"1","(-950,700)","2","standard","I13";
;
CDS_LIB"standard"
BODY_TYPE"PLUMBING"
HDL_TAP"TRUE";
"B \NAC \NWC"9;
"S \NAC"
BN"3"95;
%"TAP"
"1","(2475,2950)","0","standard","I130";
;
CDS_LIB"standard"
BODY_TYPE"PLUMBING"
HDL_TAP"TRUE";
"B \NAC \NWC"8;
"S \NAC"
BN"1"101;
%"TAP"
"1","(2475,3000)","0","standard","I131";
;
CDS_LIB"standard"
BODY_TYPE"PLUMBING"
HDL_TAP"TRUE";
"B \NAC \NWC"8;
"S \NAC"
BN"2"102;
%"TAP"
"1","(2475,3050)","0","standard","I132";
;
CDS_LIB"standard"
BODY_TYPE"PLUMBING"
HDL_TAP"TRUE";
"B \NAC \NWC"8;
"S \NAC"
BN"3"103;
%"TAP"
"1","(2475,3200)","0","standard","I133";
;
CDS_LIB"standard"
BODY_TYPE"PLUMBING"
HDL_TAP"TRUE";
"B \NAC \NWC"8;
"S \NAC"
BN"6"106;
%"TAP"
"1","(2475,3100)","0","standard","I134";
;
CDS_LIB"standard"
BODY_TYPE"PLUMBING"
HDL_TAP"TRUE";
"B \NAC \NWC"8;
"S \NAC"
BN"4"104;
%"TAP"
"1","(2475,3150)","0","standard","I135";
;
CDS_LIB"standard"
BODY_TYPE"PLUMBING"
HDL_TAP"TRUE";
"B \NAC \NWC"8;
"S \NAC"
BN"5"105;
%"TAP"
"1","(2475,3300)","0","standard","I136";
;
CDS_LIB"standard"
BODY_TYPE"PLUMBING"
HDL_TAP"TRUE";
"B \NAC \NWC"8;
"S \NAC"
BN"8"108;
%"TAP"
"1","(2475,3350)","0","standard","I137";
;
CDS_LIB"standard"
BODY_TYPE"PLUMBING"
HDL_TAP"TRUE";
"B \NAC \NWC"8;
"S \NAC"
BN"9"109;
%"TAP"
"1","(2475,3250)","0","standard","I138";
;
CDS_LIB"standard"
BODY_TYPE"PLUMBING"
HDL_TAP"TRUE";
"B \NAC \NWC"8;
"S \NAC"
BN"7"107;
%"TAP"
"1","(2475,3550)","0","standard","I139";
;
CDS_LIB"standard"
BODY_TYPE"PLUMBING"
HDL_TAP"TRUE";
"B \NAC \NWC"3;
"S \NAC"
BN"1"143;
%"TAP"
"1","(-950,850)","2","standard","I14";
;
CDS_LIB"standard"
BODY_TYPE"PLUMBING"
HDL_TAP"TRUE";
"B \NAC \NWC"9;
"S \NAC"
BN"6"92;
%"TAP"
"1","(2475,3500)","0","standard","I140";
;
CDS_LIB"standard"
BODY_TYPE"PLUMBING"
HDL_TAP"TRUE";
"B \NAC \NWC"3;
"S \NAC"
BN"0"142;
%"TAP"
"1","(2475,3700)","0","standard","I141";
;
CDS_LIB"standard"
BODY_TYPE"PLUMBING"
HDL_TAP"TRUE";
"B \NAC \NWC"3;
"S \NAC"
BN"4"146;
%"TAP"
"1","(2475,3600)","0","standard","I142";
;
CDS_LIB"standard"
BODY_TYPE"PLUMBING"
HDL_TAP"TRUE";
"B \NAC \NWC"3;
"S \NAC"
BN"2"144;
%"TAP"
"1","(2475,3650)","0","standard","I143";
;
CDS_LIB"standard"
BODY_TYPE"PLUMBING"
HDL_TAP"TRUE";
"B \NAC \NWC"3;
"S \NAC"
BN"3"145;
%"TAP"
"1","(2475,3750)","0","standard","I144";
;
CDS_LIB"standard"
BODY_TYPE"PLUMBING"
HDL_TAP"TRUE";
"B \NAC \NWC"3;
"S \NAC"
BN"5"147;
%"TAP"
"1","(2475,3800)","0","standard","I145";
;
CDS_LIB"standard"
BODY_TYPE"PLUMBING"
HDL_TAP"TRUE";
"B \NAC \NWC"3;
"S \NAC"
BN"6"148;
%"TAP"
"1","(2475,3850)","0","standard","I146";
;
CDS_LIB"standard"
BODY_TYPE"PLUMBING"
HDL_TAP"TRUE";
"B \NAC \NWC"3;
"S \NAC"
BN"7"149;
%"TAP"
"1","(2475,3950)","0","standard","I147";
;
CDS_LIB"standard"
BODY_TYPE"PLUMBING"
HDL_TAP"TRUE";
"B \NAC \NWC"3;
"S \NAC"
BN"9"151;
%"TAP"
"1","(2475,3900)","0","standard","I148";
;
CDS_LIB"standard"
BODY_TYPE"PLUMBING"
HDL_TAP"TRUE";
"B \NAC \NWC"3;
"S \NAC"
BN"8"150;
%"TAP"
"1","(2475,4050)","0","standard","I149";
;
CDS_LIB"standard"
BODY_TYPE"PLUMBING"
HDL_TAP"TRUE";
"B \NAC \NWC"4;
"S \NAC"
BN"0"132;
%"TAP"
"1","(-950,800)","2","standard","I15";
;
CDS_LIB"standard"
BODY_TYPE"PLUMBING"
HDL_TAP"TRUE";
"B \NAC \NWC"9;
"S \NAC"
BN"5"93;
%"TAP"
"1","(2475,4100)","0","standard","I150";
;
CDS_LIB"standard"
BODY_TYPE"PLUMBING"
HDL_TAP"TRUE";
"B \NAC \NWC"4;
"S \NAC"
BN"1"133;
%"TAP"
"1","(2475,4200)","0","standard","I151";
;
CDS_LIB"standard"
BODY_TYPE"PLUMBING"
HDL_TAP"TRUE";
"B \NAC \NWC"4;
"S \NAC"
BN"3"135;
%"TAP"
"1","(2475,4150)","0","standard","I152";
;
CDS_LIB"standard"
BODY_TYPE"PLUMBING"
HDL_TAP"TRUE";
"B \NAC \NWC"4;
"S \NAC"
BN"2"134;
%"TAP"
"1","(2475,4250)","0","standard","I153";
;
CDS_LIB"standard"
BODY_TYPE"PLUMBING"
HDL_TAP"TRUE";
"B \NAC \NWC"4;
"S \NAC"
BN"4"136;
%"TAP"
"1","(2475,4300)","0","standard","I154";
;
CDS_LIB"standard"
BODY_TYPE"PLUMBING"
HDL_TAP"TRUE";
"B \NAC \NWC"4;
"S \NAC"
BN"5"137;
%"TAP"
"1","(2475,4350)","0","standard","I155";
;
CDS_LIB"standard"
BODY_TYPE"PLUMBING"
HDL_TAP"TRUE";
"B \NAC \NWC"4;
"S \NAC"
BN"6"138;
%"TAP"
"1","(2475,4450)","0","standard","I156";
;
CDS_LIB"standard"
BODY_TYPE"PLUMBING"
HDL_TAP"TRUE";
"B \NAC \NWC"4;
"S \NAC"
BN"8"140;
%"TAP"
"1","(2475,4400)","0","standard","I157";
;
CDS_LIB"standard"
BODY_TYPE"PLUMBING"
HDL_TAP"TRUE";
"B \NAC \NWC"4;
"S \NAC"
BN"7"139;
%"TAP"
"1","(2475,4500)","0","standard","I158";
;
CDS_LIB"standard"
BODY_TYPE"PLUMBING"
HDL_TAP"TRUE";
"B \NAC \NWC"4;
"S \NAC"
BN"9"141;
%"TAP"
"1","(-950,950)","2","standard","I16";
;
CDS_LIB"standard"
BODY_TYPE"PLUMBING"
HDL_TAP"TRUE";
"B \NAC \NWC"10;
"S \NAC"
BN"0"90;
%"SOCKET4677_AZIF0045P001C01CS"
"15","(775,2400)","0","pure_quanta","I169";
;
PART_NUMBER"DGA^7000023"
PART_TYPE"SMLF"
MATERIAL"IO"
VALUE"SOCKET4677_AZIF0045-P001C01CS"
$LOCATION"U2"
CDS_LIB"pure_quanta"
NEEDS_NO_SIZE"TRUE"
CDS_LMAN_SYM_OUTLINE"-1100,2250,1050,-2250"
CDS_LOCATION"U2"
$SEC"15"
CDS_SEC"15";
"DDR7_SB_PAR"
$PN"DR39"99;
"DDR7_SB_ECC0"
$PN"DC35"98;
"DDR7_SB_ECC1"
$PN"DD34"97;
"DDR7_SB_ECC2"
$PN"DG35"96;
"DDR7_SB_ECC3"
$PN"DF34"95;
"DDR7_SB_ECC4"
$PN"DF38"94;
"DDR7_SB_ECC5"
$PN"DG37"93;
"DDR7_SB_ECC6"
$PN"DD38"92;
"DDR7_SB_ECC7"
$PN"DC37"91;
"DDR7_SB_DQS_DP0"
$PN"DB30"100;
"DDR7_SB_DQS_DP1"
$PN"DB24"101;
"DDR7_SB_DQS_DP2"
$PN"DJ21"102;
"DDR7_SB_DQS_DP3"
$PN"DD18"103;
"DDR7_SB_DQS_DP4"
$PN"DF36"104;
"DDR7_SB_DQS_DP5"
$PN"DF30"105;
"DDR7_SB_DQS_DP6"
$PN"DF24"106;
"DDR7_SB_DQS_DP7"
$PN"DN21"107;
"DDR7_SB_DQS_DP8"
$PN"DH18"108;
"DDR7_SB_DQS_DP9"
$PN"DB36"109;
"DDR7_SB_DQS_DN0 \B"
$PN"DD30"110;
"DDR7_SB_DQS_DN1 \B"
$PN"DD24"111;
"DDR7_SB_DQS_DN2 \B"
$PN"DL21"112;
"DDR7_SB_DQS_DN3 \B"
$PN"DB18"113;
"DDR7_SB_DQS_DN4 \B"
$PN"DH36"114;
"DDR7_SB_DQS_DN5 \B"
$PN"DH30"115;
"DDR7_SB_DQS_DN6 \B"
$PN"DH24"116;
"DDR7_SB_DQS_DN7 \B"
$PN"DR21"117;
"DDR7_SB_DQS_DN8 \B"
$PN"DF18"118;
"DDR7_SB_DQS_DN9 \B"
$PN"DD36"119;
"DDR7_SB_DQ0"
$PN"DD32"90;
"DDR7_SB_DQ1"
$PN"DC31"89;
"DDR7_SB_DQ2"
$PN"DF32"88;
"DDR7_SB_DQ3"
$PN"DG31"87;
"DDR7_SB_DQ4"
$PN"DC29"86;
"DDR7_SB_DQ5"
$PN"DF28"85;
"DDR7_SB_DQ6"
$PN"DG29"84;
"DDR7_SB_DQ7"
$PN"DD28"83;
"DDR7_SB_DQ8"
$PN"DD26"82;
"DDR7_SB_DQ9"
$PN"DC25"81;
"DDR7_SB_DQ10"
$PN"DF26"80;
"DDR7_SB_DQ11"
$PN"DG25"79;
"DDR7_SB_DQ12"
$PN"DC23"78;
"DDR7_SB_DQ13"
$PN"DD22"77;
"DDR7_SB_DQ14"
$PN"DG23"76;
"DDR7_SB_DQ15"
$PN"DF22"75;
"DDR7_SB_DQ16"
$PN"DL23"74;
"DDR7_SB_DQ17"
$PN"DK22"73;
"DDR7_SB_DQ18"
$PN"DN23"72;
"DDR7_SB_DQ19"
$PN"DP22"71;
"DDR7_SB_DQ20"
$PN"DK20"70;
"DDR7_SB_DQ21"
$PN"DL19"69;
"DDR7_SB_DQ22"
$PN"DP20"68;
"DDR7_SB_DQ23"
$PN"DN19"67;
"DDR7_SB_DQ24"
$PN"DD20"66;
"DDR7_SB_DQ25"
$PN"DC19"65;
"DDR7_SB_DQ26"
$PN"DF20"64;
"DDR7_SB_DQ27"
$PN"DG19"63;
"DDR7_SB_DQ28"
$PN"DG17"62;
"DDR7_SB_DQ29"
$PN"DA17"61;
"DDR7_SB_DQ30"
$PN"DJ17"60;
"DDR7_SB_DQ31"
$PN"DC17"59;
"DDR7_SB_CS_N0 \B"
$PN"DL37"120;
"DDR7_SB_CS_N1 \B"
$PN"DN37"121;
"DDR7_SB_CS_N2 \B"
$PN"DK38"122;
"DDR7_SB_CS_N3 \B"
$PN"DP38"123;
"DDR7_SB_CA0"
$PN"DF40"124;
"DDR7_SB_CA1"
$PN"DG41"125;
"DDR7_SB_CA2"
$PN"DL41"126;
"DDR7_SB_CA3"
$PN"DN41"127;
"DDR7_SB_CA4"
$PN"DK40"128;
"DDR7_SB_CA5"
$PN"DP40"129;
"DDR7_SB_CA6"
$PN"DJ39"130;
"DDR7_SA_PAR"
$PN"DD40"131;
"DDR7_SA_ECC0"
$PN"DD57"58;
"DDR7_SA_ECC1"
$PN"DC56"57;
"DDR7_SA_ECC2"
$PN"DF57"56;
"DDR7_SA_ECC3"
$PN"DG56"55;
"DDR7_SA_ECC4"
$PN"DC54"54;
"DDR7_SA_ECC5"
$PN"DD53"53;
"DDR7_SA_ECC6"
$PN"DG54"52;
"DDR7_SA_ECC7"
$PN"DF53"51;
"DDR7_SA_DQS_DP0"
$PN"DL76"132;
"DDR7_SA_DQS_DP1"
$PN"DD73"133;
"DDR7_SA_DQS_DP2"
$PN"DB67"134;
"DDR7_SA_DQS_DP3"
$PN"DB61"135;
"DDR7_SA_DQS_DP4"
$PN"DB55"136;
"DDR7_SA_DQS_DP5"
$PN"DN76"137;
"DDR7_SA_DQS_DP6"
$PN"DF73"138;
"DDR7_SA_DQS_DP7"
$PN"DF67"139;
"DDR7_SA_DQS_DP8"
$PN"DF61"140;
"DDR7_SA_DQS_DP9"
$PN"DF55"141;
"DDR7_SA_DQS_DN0 \B"
$PN"DJ76"142;
"DDR7_SA_DQS_DN1 \B"
$PN"DB73"143;
"DDR7_SA_DQS_DN2 \B"
$PN"DD67"144;
"DDR7_SA_DQS_DN3 \B"
$PN"DD61"145;
"DDR7_SA_DQS_DN4 \B"
$PN"DD55"146;
"DDR7_SA_DQS_DN5 \B"
$PN"DR76"147;
"DDR7_SA_DQS_DN6 \B"
$PN"DH73"148;
"DDR7_SA_DQS_DN7 \B"
$PN"DH67"149;
"DDR7_SA_DQS_DN8 \B"
$PN"DH61"150;
"DDR7_SA_DQS_DN9 \B"
$PN"DH55"151;
"DDR7_SA_DQ0"
$PN"DY79"50;
"DDR7_SA_DQ1"
$PN"DT77"49;
"DDR7_SA_DQ2"
$PN"DW78"48;
"DDR7_SA_DQ3"
$PN"DP77"47;
"DDR7_SA_DQ4"
$PN"DK75"46;
"DDR7_SA_DQ5"
$PN"DL74"45;
"DDR7_SA_DQ6"
$PN"DP75"44;
"DDR7_SA_DQ7"
$PN"DN74"43;
"DDR7_SA_DQ8"
$PN"DD75"42;
"DDR7_SA_DQ9"
$PN"DC74"41;
"DDR7_SA_DQ10"
$PN"DF75"40;
"DDR7_SA_DQ11"
$PN"DG74"39;
"DDR7_SA_DQ12"
$PN"DC72"38;
"DDR7_SA_DQ13"
$PN"DD71"37;
"DDR7_SA_DQ14"
$PN"DG72"36;
"DDR7_SA_DQ15"
$PN"DF71"35;
"DDR7_SA_DQ16"
$PN"DD69"34;
"DDR7_SA_DQ17"
$PN"DC68"33;
"DDR7_SA_DQ18"
$PN"DF69"32;
"DDR7_SA_DQ19"
$PN"DG68"31;
"DDR7_SA_DQ20"
$PN"DC66"30;
"DDR7_SA_DQ21"
$PN"DD65"29;
"DDR7_SA_DQ22"
$PN"DG66"28;
"DDR7_SA_DQ23"
$PN"DF65"27;
"DDR7_SA_DQ24"
$PN"DD63"26;
"DDR7_SA_DQ25"
$PN"DC62"25;
"DDR7_SA_DQ26"
$PN"DF63"24;
"DDR7_SA_DQ27"
$PN"DG62"23;
"DDR7_SA_DQ28"
$PN"DC60"22;
"DDR7_SA_DQ29"
$PN"DD59"21;
"DDR7_SA_DQ30"
$PN"DG60"20;
"DDR7_SA_DQ31"
$PN"DF59"19;
"DDR7_SA_CS_N0 \B"
$PN"DF51"152;
"DDR7_SA_CS_N1 \B"
$PN"DG50"153;
"DDR7_SA_CS_N2 \B"
$PN"DD51"154;
"DDR7_SA_CS_N3 \B"
$PN"DC50"155;
"DDR7_SA_CA0"
$PN"DB49"156;
"DDR7_SA_CA1"
$PN"DH49"157;
"DDR7_SA_CA2"
$PN"DC48"158;
"DDR7_SA_CA3"
$PN"DG48"159;
"DDR7_SA_CA4"
$PN"DD47"160;
"DDR7_SA_CA5"
$PN"DF47"161;
"DDR7_SA_CA6"
$PN"DC41"162;
"DDR7_CLK_DP0"
$PN"DF42"18;
"DDR7_CLK_DP1"
$PN"DB42"17;
"DDR7_CLK_DN0 \B"
$PN"DH42"16;
"DDR7_CLK_DN1 \B"
$PN"DD42"15;
"DDR7_B_RSP0"
$PN"EE48"163;
"DDR7_B_RSP1"
$PN"ED47"164;
"DDR7_A_RSP0"
$PN"EG48"165;
"DDR7_A_RSP1"
$PN"EH47"166;
"DDR7_ALERT_N \B"
$PN"CY51"167;
%"TAP"
"1","(-950,900)","2","standard","I17";
;
CDS_LIB"standard"
BODY_TYPE"PLUMBING"
HDL_TAP"TRUE";
"B \NAC \NWC"9;
"S \NAC"
BN"7"91;
%"TAP"
"1","(-950,1000)","2","standard","I18";
;
CDS_LIB"standard"
BODY_TYPE"PLUMBING"
HDL_TAP"TRUE";
"B \NAC \NWC"10;
"S \NAC"
BN"1"89;
%"TAP"
"1","(-950,1100)","2","standard","I19";
;
CDS_LIB"standard"
BODY_TYPE"PLUMBING"
HDL_TAP"TRUE";
"B \NAC \NWC"10;
"S \NAC"
BN"3"87;
%"TAP"
"1","(-950,1050)","2","standard","I20";
;
CDS_LIB"standard"
BODY_TYPE"PLUMBING"
HDL_TAP"TRUE";
"B \NAC \NWC"10;
"S \NAC"
BN"2"88;
%"TAP"
"1","(-950,1150)","2","standard","I21";
;
CDS_LIB"standard"
BODY_TYPE"PLUMBING"
HDL_TAP"TRUE";
"B \NAC \NWC"10;
"S \NAC"
BN"4"86;
%"TAP"
"1","(-950,1250)","2","standard","I22";
;
CDS_LIB"standard"
BODY_TYPE"PLUMBING"
HDL_TAP"TRUE";
"B \NAC \NWC"10;
"S \NAC"
BN"6"84;
%"TAP"
"1","(-950,1200)","2","standard","I23";
;
CDS_LIB"standard"
BODY_TYPE"PLUMBING"
HDL_TAP"TRUE";
"B \NAC \NWC"10;
"S \NAC"
BN"5"85;
%"TAP"
"1","(-950,1350)","2","standard","I24";
;
CDS_LIB"standard"
BODY_TYPE"PLUMBING"
HDL_TAP"TRUE";
"B \NAC \NWC"10;
"S \NAC"
BN"8"82;
%"TAP"
"1","(-950,1300)","2","standard","I25";
;
CDS_LIB"standard"
BODY_TYPE"PLUMBING"
HDL_TAP"TRUE";
"B \NAC \NWC"10;
"S \NAC"
BN"7"83;
%"TAP"
"1","(-950,1400)","2","standard","I26";
;
CDS_LIB"standard"
BODY_TYPE"PLUMBING"
HDL_TAP"TRUE";
"B \NAC \NWC"10;
"S \NAC"
BN"9"81;
%"TAP"
"1","(-950,1450)","2","standard","I27";
;
CDS_LIB"standard"
BODY_TYPE"PLUMBING"
HDL_TAP"TRUE";
"B \NAC \NWC"10;
"S \NAC"
BN"10"80;
%"TAP"
"1","(-950,1500)","2","standard","I28";
;
CDS_LIB"standard"
BODY_TYPE"PLUMBING"
HDL_TAP"TRUE";
"B \NAC \NWC"10;
"S \NAC"
BN"11"79;
%"TAP"
"1","(-950,1600)","2","standard","I29";
;
CDS_LIB"standard"
BODY_TYPE"PLUMBING"
HDL_TAP"TRUE";
"B \NAC \NWC"10;
"S \NAC"
BN"13"77;
%"TAP"
"1","(-950,350)","2","standard","I3";
;
CDS_LIB"standard"
BODY_TYPE"PLUMBING"
HDL_TAP"TRUE";
"B \NAC \NWC"14;
"S \NAC"
BN"1"15;
%"TAP"
"1","(-950,1550)","2","standard","I30";
;
CDS_LIB"standard"
BODY_TYPE"PLUMBING"
HDL_TAP"TRUE";
"B \NAC \NWC"10;
"S \NAC"
BN"12"78;
%"TAP"
"1","(-950,1650)","2","standard","I31";
;
CDS_LIB"standard"
BODY_TYPE"PLUMBING"
HDL_TAP"TRUE";
"B \NAC \NWC"10;
"S \NAC"
BN"14"76;
%"TAP"
"1","(-950,1700)","2","standard","I32";
;
CDS_LIB"standard"
BODY_TYPE"PLUMBING"
HDL_TAP"TRUE";
"B \NAC \NWC"10;
"S \NAC"
BN"15"75;
%"TAP"
"1","(-950,1750)","2","standard","I33";
;
CDS_LIB"standard"
BODY_TYPE"PLUMBING"
HDL_TAP"TRUE";
"B \NAC \NWC"10;
"S \NAC"
BN"16"74;
%"TAP"
"1","(-950,1850)","2","standard","I34";
;
CDS_LIB"standard"
BODY_TYPE"PLUMBING"
HDL_TAP"TRUE";
"B \NAC \NWC"10;
"S \NAC"
BN"18"72;
%"TAP"
"1","(-950,1900)","2","standard","I35";
;
CDS_LIB"standard"
BODY_TYPE"PLUMBING"
HDL_TAP"TRUE";
"B \NAC \NWC"10;
"S \NAC"
BN"19"71;
%"TAP"
"1","(-950,1800)","2","standard","I36";
;
CDS_LIB"standard"
BODY_TYPE"PLUMBING"
HDL_TAP"TRUE";
"B \NAC \NWC"10;
"S \NAC"
BN"17"73;
%"TAP"
"1","(-950,2000)","2","standard","I37";
;
CDS_LIB"standard"
BODY_TYPE"PLUMBING"
HDL_TAP"TRUE";
"B \NAC \NWC"10;
"S \NAC"
BN"21"69;
%"TAP"
"1","(-950,1950)","2","standard","I38";
;
CDS_LIB"standard"
BODY_TYPE"PLUMBING"
HDL_TAP"TRUE";
"B \NAC \NWC"10;
"S \NAC"
BN"20"70;
%"TAP"
"1","(-950,2050)","2","standard","I39";
;
CDS_LIB"standard"
BODY_TYPE"PLUMBING"
HDL_TAP"TRUE";
"B \NAC \NWC"10;
"S \NAC"
BN"22"68;
%"TAP"
"1","(-950,300)","2","standard","I4";
;
CDS_LIB"standard"
BODY_TYPE"PLUMBING"
HDL_TAP"TRUE";
"B \NAC \NWC"14;
"S \NAC"
BN"0"16;
%"TAP"
"1","(-950,2100)","2","standard","I40";
;
CDS_LIB"standard"
BODY_TYPE"PLUMBING"
HDL_TAP"TRUE";
"B \NAC \NWC"10;
"S \NAC"
BN"23"67;
%"TAP"
"1","(-950,2150)","2","standard","I41";
;
CDS_LIB"standard"
BODY_TYPE"PLUMBING"
HDL_TAP"TRUE";
"B \NAC \NWC"10;
"S \NAC"
BN"24"66;
%"TAP"
"1","(-950,2200)","2","standard","I42";
;
CDS_LIB"standard"
BODY_TYPE"PLUMBING"
HDL_TAP"TRUE";
"B \NAC \NWC"10;
"S \NAC"
BN"25"65;
%"TAP"
"1","(-950,2250)","2","standard","I43";
;
CDS_LIB"standard"
BODY_TYPE"PLUMBING"
HDL_TAP"TRUE";
"B \NAC \NWC"10;
"S \NAC"
BN"26"64;
%"TAP"
"1","(-950,2300)","2","standard","I44";
;
CDS_LIB"standard"
BODY_TYPE"PLUMBING"
HDL_TAP"TRUE";
"B \NAC \NWC"10;
"S \NAC"
BN"27"63;
%"TAP"
"1","(-950,2350)","2","standard","I45";
;
CDS_LIB"standard"
BODY_TYPE"PLUMBING"
HDL_TAP"TRUE";
"B \NAC \NWC"10;
"S \NAC"
BN"28"62;
%"TAP"
"1","(-950,2400)","2","standard","I46";
;
CDS_LIB"standard"
BODY_TYPE"PLUMBING"
HDL_TAP"TRUE";
"B \NAC \NWC"10;
"S \NAC"
BN"29"61;
%"TAP"
"1","(-950,2500)","2","standard","I47";
;
CDS_LIB"standard"
BODY_TYPE"PLUMBING"
HDL_TAP"TRUE";
"B \NAC \NWC"10;
"S \NAC"
BN"31"59;
%"TAP"
"1","(-950,2450)","2","standard","I48";
;
CDS_LIB"standard"
BODY_TYPE"PLUMBING"
HDL_TAP"TRUE";
"B \NAC \NWC"10;
"S \NAC"
BN"30"60;
%"TAP"
"1","(-950,2650)","2","standard","I49";
;
CDS_LIB"standard"
BODY_TYPE"PLUMBING"
HDL_TAP"TRUE";
"B \NAC \NWC"11;
"S \NAC"
BN"2"56;
%"TAP"
"1","(-950,600)","2","standard","I5";
;
CDS_LIB"standard"
BODY_TYPE"PLUMBING"
HDL_TAP"TRUE";
"B \NAC \NWC"9;
"S \NAC"
BN"1"97;
%"TAP"
"1","(-950,2600)","2","standard","I50";
;
CDS_LIB"standard"
BODY_TYPE"PLUMBING"
HDL_TAP"TRUE";
"B \NAC \NWC"11;
"S \NAC"
BN"1"57;
%"TAP"
"1","(-950,2550)","2","standard","I51";
;
CDS_LIB"standard"
BODY_TYPE"PLUMBING"
HDL_TAP"TRUE";
"B \NAC \NWC"11;
"S \NAC"
BN"0"58;
%"TAP"
"1","(-950,2750)","2","standard","I54";
;
CDS_LIB"standard"
BODY_TYPE"PLUMBING"
HDL_TAP"TRUE";
"B \NAC \NWC"11;
"S \NAC"
BN"4"54;
%"TAP"
"1","(-950,2800)","2","standard","I55";
;
CDS_LIB"standard"
BODY_TYPE"PLUMBING"
HDL_TAP"TRUE";
"B \NAC \NWC"11;
"S \NAC"
BN"5"53;
%"TAP"
"1","(-950,2700)","2","standard","I56";
;
CDS_LIB"standard"
BODY_TYPE"PLUMBING"
HDL_TAP"TRUE";
"B \NAC \NWC"11;
"S \NAC"
BN"3"55;
%"TAP"
"1","(-950,2900)","2","standard","I57";
;
CDS_LIB"standard"
BODY_TYPE"PLUMBING"
HDL_TAP"TRUE";
"B \NAC \NWC"11;
"S \NAC"
BN"7"51;
%"TAP"
"1","(-950,2850)","2","standard","I58";
;
CDS_LIB"standard"
BODY_TYPE"PLUMBING"
HDL_TAP"TRUE";
"B \NAC \NWC"11;
"S \NAC"
BN"6"52;
%"TAP"
"1","(-950,3000)","2","standard","I59";
;
CDS_LIB"standard"
BODY_TYPE"PLUMBING"
HDL_TAP"TRUE";
"B \NAC \NWC"12;
"S \NAC"
BN"1"49;
%"TAP"
"1","(-950,550)","2","standard","I6";
;
CDS_LIB"standard"
BODY_TYPE"PLUMBING"
HDL_TAP"TRUE";
"B \NAC \NWC"9;
"S \NAC"
BN"0"98;
%"TAP"
"1","(-950,2950)","2","standard","I60";
;
CDS_LIB"standard"
BODY_TYPE"PLUMBING"
HDL_TAP"TRUE";
"B \NAC \NWC"12;
"S \NAC"
BN"0"50;
%"TAP"
"1","(-950,3050)","2","standard","I61";
;
CDS_LIB"standard"
BODY_TYPE"PLUMBING"
HDL_TAP"TRUE";
"B \NAC \NWC"12;
"S \NAC"
BN"2"48;
%"TAP"
"1","(-950,3150)","2","standard","I62";
;
CDS_LIB"standard"
BODY_TYPE"PLUMBING"
HDL_TAP"TRUE";
"B \NAC \NWC"12;
"S \NAC"
BN"4"46;
%"TAP"
"1","(-950,3100)","2","standard","I63";
;
CDS_LIB"standard"
BODY_TYPE"PLUMBING"
HDL_TAP"TRUE";
"B \NAC \NWC"12;
"S \NAC"
BN"3"47;
%"TAP"
"1","(-950,3200)","2","standard","I64";
;
CDS_LIB"standard"
BODY_TYPE"PLUMBING"
HDL_TAP"TRUE";
"B \NAC \NWC"12;
"S \NAC"
BN"5"45;
%"TAP"
"1","(-950,3300)","2","standard","I65";
;
CDS_LIB"standard"
BODY_TYPE"PLUMBING"
HDL_TAP"TRUE";
"B \NAC \NWC"12;
"S \NAC"
BN"7"43;
%"TAP"
"1","(-950,3250)","2","standard","I66";
;
CDS_LIB"standard"
BODY_TYPE"PLUMBING"
HDL_TAP"TRUE";
"B \NAC \NWC"12;
"S \NAC"
BN"6"44;
%"TAP"
"1","(-950,3400)","2","standard","I67";
;
CDS_LIB"standard"
BODY_TYPE"PLUMBING"
HDL_TAP"TRUE";
"B \NAC \NWC"12;
"S \NAC"
BN"9"41;
%"TAP"
"1","(-950,3350)","2","standard","I68";
;
CDS_LIB"standard"
BODY_TYPE"PLUMBING"
HDL_TAP"TRUE";
"B \NAC \NWC"12;
"S \NAC"
BN"8"42;
%"TAP"
"1","(-950,3450)","2","standard","I69";
;
CDS_LIB"standard"
BODY_TYPE"PLUMBING"
HDL_TAP"TRUE";
"B \NAC \NWC"12;
"S \NAC"
BN"10"40;
%"TAP"
"1","(-950,400)","2","standard","I7";
;
CDS_LIB"standard"
BODY_TYPE"PLUMBING"
HDL_TAP"TRUE";
"B \NAC \NWC"13;
"S \NAC"
BN"0"18;
%"TAP"
"1","(-950,3500)","2","standard","I70";
;
CDS_LIB"standard"
BODY_TYPE"PLUMBING"
HDL_TAP"TRUE";
"B \NAC \NWC"12;
"S \NAC"
BN"11"39;
%"TAP"
"1","(-950,3550)","2","standard","I71";
;
CDS_LIB"standard"
BODY_TYPE"PLUMBING"
HDL_TAP"TRUE";
"B \NAC \NWC"12;
"S \NAC"
BN"12"38;
%"TAP"
"1","(-950,3650)","2","standard","I72";
;
CDS_LIB"standard"
BODY_TYPE"PLUMBING"
HDL_TAP"TRUE";
"B \NAC \NWC"12;
"S \NAC"
BN"14"36;
%"TAP"
"1","(-950,3600)","2","standard","I73";
;
CDS_LIB"standard"
BODY_TYPE"PLUMBING"
HDL_TAP"TRUE";
"B \NAC \NWC"12;
"S \NAC"
BN"13"37;
%"TAP"
"1","(-950,3700)","2","standard","I74";
;
CDS_LIB"standard"
BODY_TYPE"PLUMBING"
HDL_TAP"TRUE";
"B \NAC \NWC"12;
"S \NAC"
BN"15"35;
%"TAP"
"1","(-950,3750)","2","standard","I75";
;
CDS_LIB"standard"
BODY_TYPE"PLUMBING"
HDL_TAP"TRUE";
"B \NAC \NWC"12;
"S \NAC"
BN"16"34;
%"TAP"
"1","(-950,3800)","2","standard","I76";
;
CDS_LIB"standard"
BODY_TYPE"PLUMBING"
HDL_TAP"TRUE";
"B \NAC \NWC"12;
"S \NAC"
BN"17"33;
%"TAP"
"1","(-950,3900)","2","standard","I77";
;
CDS_LIB"standard"
BODY_TYPE"PLUMBING"
HDL_TAP"TRUE";
"B \NAC \NWC"12;
"S \NAC"
BN"19"31;
%"TAP"
"1","(-950,3950)","2","standard","I78";
;
CDS_LIB"standard"
BODY_TYPE"PLUMBING"
HDL_TAP"TRUE";
"B \NAC \NWC"12;
"S \NAC"
BN"20"30;
%"TAP"
"1","(-950,3850)","2","standard","I79";
;
CDS_LIB"standard"
BODY_TYPE"PLUMBING"
HDL_TAP"TRUE";
"B \NAC \NWC"12;
"S \NAC"
BN"18"32;
%"TAP"
"1","(-950,450)","2","standard","I8";
;
CDS_LIB"standard"
BODY_TYPE"PLUMBING"
HDL_TAP"TRUE";
"B \NAC \NWC"13;
"S \NAC"
BN"1"17;
%"TAP"
"1","(-950,4050)","2","standard","I80";
;
CDS_LIB"standard"
BODY_TYPE"PLUMBING"
HDL_TAP"TRUE";
"B \NAC \NWC"12;
"S \NAC"
BN"22"28;
%"TAP"
"1","(-950,4000)","2","standard","I81";
;
CDS_LIB"standard"
BODY_TYPE"PLUMBING"
HDL_TAP"TRUE";
"B \NAC \NWC"12;
"S \NAC"
BN"21"29;
%"TAP"
"1","(-950,4150)","2","standard","I82";
;
CDS_LIB"standard"
BODY_TYPE"PLUMBING"
HDL_TAP"TRUE";
"B \NAC \NWC"12;
"S \NAC"
BN"24"26;
%"TAP"
"1","(-950,4100)","2","standard","I83";
;
CDS_LIB"standard"
BODY_TYPE"PLUMBING"
HDL_TAP"TRUE";
"B \NAC \NWC"12;
"S \NAC"
BN"23"27;
%"TAP"
"1","(-950,4200)","2","standard","I84";
;
CDS_LIB"standard"
BODY_TYPE"PLUMBING"
HDL_TAP"TRUE";
"B \NAC \NWC"12;
"S \NAC"
BN"25"25;
%"TAP"
"1","(-950,4300)","2","standard","I85";
;
CDS_LIB"standard"
BODY_TYPE"PLUMBING"
HDL_TAP"TRUE";
"B \NAC \NWC"12;
"S \NAC"
BN"27"23;
%"TAP"
"1","(-950,4250)","2","standard","I86";
;
CDS_LIB"standard"
BODY_TYPE"PLUMBING"
HDL_TAP"TRUE";
"B \NAC \NWC"12;
"S \NAC"
BN"26"24;
%"TAP"
"1","(-950,4350)","2","standard","I87";
;
CDS_LIB"standard"
BODY_TYPE"PLUMBING"
HDL_TAP"TRUE";
"B \NAC \NWC"12;
"S \NAC"
BN"28"22;
%"TAP"
"1","(-950,4400)","2","standard","I88";
;
CDS_LIB"standard"
BODY_TYPE"PLUMBING"
HDL_TAP"TRUE";
"B \NAC \NWC"12;
"S \NAC"
BN"29"21;
%"TAP"
"1","(-950,4450)","2","standard","I89";
;
CDS_LIB"standard"
BODY_TYPE"PLUMBING"
HDL_TAP"TRUE";
"B \NAC \NWC"12;
"S \NAC"
BN"30"20;
%"TAP"
"1","(-950,650)","2","standard","I9";
;
CDS_LIB"standard"
BODY_TYPE"PLUMBING"
HDL_TAP"TRUE";
"B \NAC \NWC"9;
"S \NAC"
BN"2"96;
%"TAP"
"1","(-950,4500)","2","standard","I90";
;
CDS_LIB"standard"
BODY_TYPE"PLUMBING"
HDL_TAP"TRUE";
"B \NAC \NWC"12;
"S \NAC"
BN"31"19;
%"TAP"
"1","(2475,750)","0","standard","I97";
;
CDS_LIB"standard"
BODY_TYPE"PLUMBING"
HDL_TAP"TRUE";
"B \NAC \NWC"6;
"S \NAC"
BN"0"120;
%"TAP"
"1","(2475,900)","0","standard","I98";
;
CDS_LIB"standard"
BODY_TYPE"PLUMBING"
HDL_TAP"TRUE";
"B \NAC \NWC"6;
"S \NAC"
BN"3"123;
%"TAP"
"1","(2475,800)","0","standard","I99";
;
CDS_LIB"standard"
BODY_TYPE"PLUMBING"
HDL_TAP"TRUE";
"B \NAC \NWC"6;
"S \NAC"
BN"1"121;
END.
